# T6G (Grand Teton) — schematic netlist excerpt (pin names and nets, part order shuffled) for the footprints in the layout excerpt that follows; sources: Cadence DE-HDL packaged netlist, KiCad conversion of 04192023_DAF0TMB3IC0_F0TG_MB_C_brd_V02_OCP.brd

R8241  Q_RES  0 5% CHIP  pkg 0402LF  page 217 : A = PVDDCR_CPU1_P1_OCP_N ; B = PVDDCR_CPU1_P1_OCP_N_R
PC333  Q_CAP  0.22UF 16V 10% X7R  pkg 0402  page 215 : A = SW_PVDDCR_SOC_P1_BOOT1_RC ; B = SW_PVDDCR_SOC_P1_PH1

(kicad_pcb
	(version 20260206)
	(generator "pcbnew")
	(generator_version "10.0")
	(general
		(thickness 1.6)
		(legacy_teardrops no)
	)
	(paper "A4")
	(title_block
		(title "04192023_DAF0TMB3IC0_F0TG_MB_C_brd_V02_OCP.brd")
		(comment 1 "Grand Teton / footprints 4400-4401 of 8354")
	)
	(layers
		(0 "F.Cu" signal "TOP")
		(4 "In1.Cu" signal "GND")
		(6 "In2.Cu" signal "IN1")
		(8 "In3.Cu" signal "GND1")
		(10 "In4.Cu" signal "IN2")
		(12 "In5.Cu" signal "GND2")
		(14 "In6.Cu" signal "IN3")
		(16 "In7.Cu" signal "GND3")
		(18 "In8.Cu" signal "VCC")
		(20 "In9.Cu" signal "VCC1")
		(22 "In10.Cu" signal "GND4")
		(24 "In11.Cu" signal "IN4")
		(26 "In12.Cu" signal "GND5")
		(28 "In13.Cu" signal "IN5")
		(30 "In14.Cu" signal "GND6")
		(32 "In15.Cu" signal "IN6")
		(34 "In16.Cu" signal "GND7")
		(2 "B.Cu" signal "BOTTOM")
		(9 "F.Adhes" user "F.Adhesive")
		(11 "B.Adhes" user "B.Adhesive")
		(13 "F.Paste" user "Package Geometry/Pastemask Top")
		(15 "B.Paste" user "Package Geometry/Pastemask Bottom")
		(5 "F.SilkS" user "Ref Des/Silkscreen Top")
		(7 "B.SilkS" user "Ref Des/Silkscreen Bottom")
		(1 "F.Mask" user "Board Geometry/Soldermask Top")
		(3 "B.Mask" user "Board Geometry/Soldermask Bottom")
		(17 "Dwgs.User" user "User.Drawings")
		(19 "Cmts.User" user "User.Comments")
		(21 "Eco1.User" user "User.Eco1")
		(23 "Eco2.User" user "User.Eco2")
		(25 "Edge.Cuts" user "Board Geometry/Outline")
		(27 "Margin" user)
		(31 "F.CrtYd" user "Package Geometry/Place Bound Top")
		(29 "B.CrtYd" user "Package Geometry/Place Bound Bottom")
		(35 "F.Fab" user "Ref Des/Assembly Top")
		(33 "B.Fab" user "Ref Des/Assembly Bottom")
	)
	(footprint ""
		(layer "F.Cu")
		(at 113.899696 -167.2717 90)
		(property "Reference" "PC333"
			(at 0 0 90)
			(layer "F.SilkS")
			(hide yes)
			(effects
				(font
					(size 1.27 1.27)
				)
			)
		)
		(property "Value" ""
			(at 0 0 90)
			(layer "F.Fab")
			(effects
				(font
					(size 1.27 1.27)
				)
			)
		)
		(duplicate_pad_numbers_are_jumpers no)
		(fp_line
			(start 0.7874 -0.4064)
			(end 0.7874 0.4064)
			(stroke
				(width 0.1524)
				(type default)
			)
			(layer "F.SilkS")
		)
		(fp_line
			(start -0.7874 -0.4064)
			(end 0.7874 -0.4064)
			(stroke
				(width 0.1524)
				(type default)
			)
			(layer "F.SilkS")
		)
		(fp_line
			(start 0.7874 0.4064)
			(end -0.7874 0.4064)
			(stroke
				(width 0.1524)
				(type default)
			)
			(layer "F.SilkS")
		)
		(fp_line
			(start -0.7874 0.4064)
			(end -0.7874 -0.4064)
			(stroke
				(width 0.1524)
				(type default)
			)
			(layer "F.SilkS")
		)
		(fp_line
			(start -0.12065 -0.305054)
			(end -0.12065 -0.2794)
			(stroke
				(width 0.1)
				(type default)
			)
			(layer "F.Fab")
		)
		(fp_line
			(start -0.67945 -0.305054)
			(end -0.12065 -0.305054)
			(stroke
				(width 0.1)
				(type default)
			)
			(layer "F.Fab")
		)
		(fp_line
			(start 0.67945 -0.3048)
			(end 0.67945 0.3048)
			(stroke
				(width 0.1)
				(type default)
			)
			(layer "F.Fab")
		)
		(fp_line
			(start 0.12065 -0.3048)
			(end 0.67945 -0.3048)
			(stroke
				(width 0.1)
				(type default)
			)
			(layer "F.Fab")
		)
		(fp_line
			(start 0.12065 -0.2794)
			(end 0.12065 -0.3048)
			(stroke
				(width 0.1)
				(type default)
			)
			(layer "F.Fab")
		)
		(fp_line
			(start -0.12065 -0.2794)
			(end 0.12065 -0.2794)
			(stroke
				(width 0.1)
				(type default)
			)
			(layer "F.Fab")
		)
		(fp_line
			(start 0.120396 0.2794)
			(end -0.12065 0.2794)
			(stroke
				(width 0.1)
				(type default)
			)
			(layer "F.Fab")
		)
		(fp_line
			(start -0.12065 0.2794)
			(end -0.12065 0.3048)
			(stroke
				(width 0.1)
				(type default)
			)
			(layer "F.Fab")
		)
		(fp_line
			(start 0.67945 0.3048)
			(end 0.120396 0.3048)
			(stroke
				(width 0.1)
				(type default)
			)
			(layer "F.Fab")
		)
		(fp_line
			(start 0.120396 0.3048)
			(end 0.120396 0.2794)
			(stroke
				(width 0.1)
				(type default)
			)
			(layer "F.Fab")
		)
		(fp_line
			(start -0.12065 0.3048)
			(end -0.67945 0.3048)
			(stroke
				(width 0.1)
				(type default)
			)
			(layer "F.Fab")
		)
		(fp_line
			(start -0.67945 0.3048)
			(end -0.67945 -0.305054)
			(stroke
				(width 0.1)
				(type default)
			)
			(layer "F.Fab")
		)
		(pad "1" smd circle
			(at -0.40005 0 90)
			(size 0 0)
			(layers "F.Cu" "F.Mask" "F.Paste")
			(net "SW_PVDDCR_SOC_P1_BOOT1_RC")
		)
		(pad "2" smd circle
			(at 0.40005 0 90)
			(size 0 0)
			(layers "F.Cu" "F.Mask" "F.Paste")
			(net "SW_PVDDCR_SOC_P1_PH1")
		)
	)
	(footprint ""
		(layer "F.Cu")
		(at 37.211 -361.061 180)
		(property "Reference" "R8241"
			(at 0 0 180)
			(layer "F.SilkS")
			(hide yes)
			(effects
				(font
					(size 1.27 1.27)
				)
			)
		)
		(property "Value" ""
			(at 0 0 180)
			(layer "F.Fab")
			(effects
				(font
					(size 1.27 1.27)
				)
			)
		)
		(duplicate_pad_numbers_are_jumpers no)
		(fp_line
			(start 0.7874 0.4064)
			(end -0.7874 0.4064)
			(stroke
				(width 0.1524)
				(type default)
			)
			(layer "F.SilkS")
		)
		(fp_line
			(start 0.7874 -0.4064)
			(end 0.7874 0.4064)
			(stroke
				(width 0.1524)
				(type default)
			)
			(layer "F.SilkS")
		)
		(fp_line
			(start -0.7874 0.4064)
			(end -0.7874 -0.4064)
			(stroke
				(width 0.1524)
				(type default)
			)
			(layer "F.SilkS")
		)
		(fp_line
			(start -0.7874 -0.4064)
			(end 0.7874 -0.4064)
			(stroke
				(width 0.1524)
				(type default)
			)
			(layer "F.SilkS")
		)
		(fp_line
			(start 0.67945 0.3048)
			(end 0.120396 0.3048)
			(stroke
				(width 0.1)
				(type default)
			)
			(layer "F.Fab")
		)
		(fp_line
			(start 0.67945 -0.3048)
			(end 0.67945 0.3048)
			(stroke
				(width 0.1)
				(type default)
			)
			(layer "F.Fab")
		)
		(fp_line
			(start 0.12065 -0.2794)
			(end 0.12065 -0.3048)
			(stroke
				(width 0.1)
				(type default)
			)
			(layer "F.Fab")
		)
		(fp_line
			(start 0.12065 -0.3048)
			(end 0.67945 -0.3048)
			(stroke
				(width 0.1)
				(type default)
			)
			(layer "F.Fab")
		)
		(fp_line
			(start 0.120396 0.3048)
			(end 0.120396 0.2794)
			(stroke
				(width 0.1)
				(type default)
			)
			(layer "F.Fab")
		)
		(fp_line
			(start 0.120396 0.2794)
			(end -0.12065 0.2794)
			(stroke
				(width 0.1)
				(type default)
			)
			(layer "F.Fab")
		)
		(fp_line
			(start -0.12065 0.3048)
			(end -0.67945 0.3048)
			(stroke
				(width 0.1)
				(type default)
			)
			(layer "F.Fab")
		)
		(fp_line
			(start -0.12065 0.2794)
			(end -0.12065 0.3048)
			(stroke
				(width 0.1)
				(type default)
			)
			(layer "F.Fab")
		)
		(fp_line
			(start -0.12065 -0.2794)
			(end 0.12065 -0.2794)
			(stroke
				(width 0.1)
				(type default)
			)
			(layer "F.Fab")
		)
		(fp_line
			(start -0.12065 -0.305054)
			(end -0.12065 -0.2794)
			(stroke
				(width 0.1)
				(type default)
			)
			(layer "F.Fab")
		)
		(fp_line
			(start -0.67945 0.3048)
			(end -0.67945 -0.305054)
			(stroke
				(width 0.1)
				(type default)
			)
			(layer "F.Fab")
		)
		(fp_line
			(start -0.67945 -0.305054)
			(end -0.12065 -0.305054)
			(stroke
				(width 0.1)
				(type default)
			)
			(layer "F.Fab")
		)
		(pad "1" smd circle
			(at -0.40005 0 180)
			(size 0 0)
			(layers "F.Cu" "F.Mask" "F.Paste")
			(net "PVDDCR_CPU1_P1_OCP_N")
		)
		(pad "2" smd circle
			(at 0.40005 0 180)
			(size 0 0)
			(layers "F.Cu" "F.Mask" "F.Paste")
			(net "PVDDCR_CPU1_P1_OCP_N_R")
		)
	)
)
